#ISCELL
  pure_quanta quanta_title_block_c *
  *
#CELL
  pure_quanta socket4677_azif0045p001c01cs *
  page35_i102
#ISCELL
  logical_power universal_gnd *
  page35_i104
